# S9S_MB_2U (Grand Teton) — schematic netlist excerpt (pin names and nets, part order shuffled) for the footprints in the layout excerpt that follows; sources: Cadence DE-HDL packaged netlist, KiCad conversion of 03242023_DA0F0TMBIJ0_F0T_Motherboard_J_brd_V01_OCP.brd

R743  Q_RES  150 1% CHIP  pkg 0402LF  page 133 : A = PVNN_TERM_CPU1 ; B = JTAG_MUX_CPU1_GTL_TDI
R3642  Q_RES  10K 1% CHIP  pkg 0402LF  page 208 : A = P3V3_AUX ; B = CK440Q_OE_5

(kicad_pcb
	(version 20260206)
	(generator "pcbnew")
	(generator_version "10.0")
	(general
		(thickness 1.6)
		(legacy_teardrops no)
	)
	(paper "A4")
	(title_block
		(title "03242023_DA0F0TMBIJ0_F0T_Motherboard_J_brd_V01_OCP.brd")
		(comment 1 "Grand Teton / footprints 4980-4981 of 6105")
	)
	(layers
		(0 "F.Cu" signal "TOP")
		(4 "In1.Cu" signal "GND")
		(6 "In2.Cu" signal "IN1")
		(8 "In3.Cu" signal "GND1")
		(10 "In4.Cu" signal "IN2")
		(12 "In5.Cu" signal "GND2")
		(14 "In6.Cu" signal "IN3")
		(16 "In7.Cu" signal "GND3")
		(18 "In8.Cu" signal "VCC")
		(20 "In9.Cu" signal "VCC1")
		(22 "In10.Cu" signal "GND4")
		(24 "In11.Cu" signal "IN4")
		(26 "In12.Cu" signal "GND5")
		(28 "In13.Cu" signal "IN5")
		(30 "In14.Cu" signal "GND6")
		(32 "In15.Cu" signal "IN6")
		(34 "In16.Cu" signal "GND7")
		(2 "B.Cu" signal "BOTTOM")
		(9 "F.Adhes" user "F.Adhesive")
		(11 "B.Adhes" user "B.Adhesive")
		(13 "F.Paste" user "Package Geometry/Pastemask Top")
		(15 "B.Paste" user "Package Geometry/Pastemask Bottom")
		(5 "F.SilkS" user "Ref Des/Silkscreen Top")
		(7 "B.SilkS" user "Ref Des/Silkscreen Bottom")
		(1 "F.Mask" user "Board Geometry/Soldermask Top")
		(3 "B.Mask" user "Board Geometry/Soldermask Bottom")
		(17 "Dwgs.User" user "User.Drawings")
		(19 "Cmts.User" user "User.Comments")
		(21 "Eco1.User" user "User.Eco1")
		(23 "Eco2.User" user "User.Eco2")
		(25 "Edge.Cuts" user "Board Geometry/Outline")
		(27 "Margin" user)
		(31 "F.CrtYd" user "Package Geometry/Place Bound Top")
		(29 "B.CrtYd" user "Package Geometry/Place Bound Bottom")
		(35 "F.Fab" user "Ref Des/Assembly Top")
		(33 "B.Fab" user "Ref Des/Assembly Bottom")
	)
	(footprint ""
		(layer "B.Cu")
		(at 98.273108 -190.705232 -90)
		(property "Reference" "R743"
			(at 0 0 90)
			(layer "B.SilkS")
			(hide yes)
			(effects
				(font
					(size 1.27 1.27)
				)
				(justify mirror)
			)
		)
		(property "Value" ""
			(at 0 0 90)
			(layer "B.Fab")
			(effects
				(font
					(size 1.27 1.27)
				)
				(justify mirror)
			)
		)
		(duplicate_pad_numbers_are_jumpers no)
		(fp_line
			(start -0.7874 0.4064)
			(end 0.7874 0.4064)
			(stroke
				(width 0.1524)
				(type default)
			)
			(layer "B.SilkS")
		)
		(fp_line
			(start 0.7874 0.4064)
			(end 0.7874 -0.4064)
			(stroke
				(width 0.1524)
				(type default)
			)
			(layer "B.SilkS")
		)
		(fp_line
			(start -0.7874 -0.4064)
			(end -0.7874 0.4064)
			(stroke
				(width 0.1524)
				(type default)
			)
			(layer "B.SilkS")
		)
		(fp_line
			(start 0.7874 -0.4064)
			(end -0.7874 -0.4064)
			(stroke
				(width 0.1524)
				(type default)
			)
			(layer "B.SilkS")
		)
		(fp_line
			(start -0.67945 0.3048)
			(end -0.120396 0.3048)
			(stroke
				(width 0.1)
				(type default)
			)
			(layer "B.Fab")
		)
		(fp_line
			(start -0.120396 0.3048)
			(end -0.120396 0.2794)
			(stroke
				(width 0.1)
				(type default)
			)
			(layer "B.Fab")
		)
		(fp_line
			(start 0.12065 0.3048)
			(end 0.67945 0.3048)
			(stroke
				(width 0.1)
				(type default)
			)
			(layer "B.Fab")
		)
		(fp_line
			(start 0.67945 0.3048)
			(end 0.67945 -0.305054)
			(stroke
				(width 0.1)
				(type default)
			)
			(layer "B.Fab")
		)
		(fp_line
			(start -0.120396 0.2794)
			(end 0.12065 0.2794)
			(stroke
				(width 0.1)
				(type default)
			)
			(layer "B.Fab")
		)
		(fp_line
			(start 0.12065 0.2794)
			(end 0.12065 0.3048)
			(stroke
				(width 0.1)
				(type default)
			)
			(layer "B.Fab")
		)
		(fp_line
			(start -0.12065 -0.2794)
			(end -0.12065 -0.3048)
			(stroke
				(width 0.1)
				(type default)
			)
			(layer "B.Fab")
		)
		(fp_line
			(start 0.12065 -0.2794)
			(end -0.12065 -0.2794)
			(stroke
				(width 0.1)
				(type default)
			)
			(layer "B.Fab")
		)
		(fp_line
			(start -0.67945 -0.3048)
			(end -0.67945 0.3048)
			(stroke
				(width 0.1)
				(type default)
			)
			(layer "B.Fab")
		)
		(fp_line
			(start -0.12065 -0.3048)
			(end -0.67945 -0.3048)
			(stroke
				(width 0.1)
				(type default)
			)
			(layer "B.Fab")
		)
		(fp_line
			(start 0.12065 -0.305054)
			(end 0.12065 -0.2794)
			(stroke
				(width 0.1)
				(type default)
			)
			(layer "B.Fab")
		)
		(fp_line
			(start 0.67945 -0.305054)
			(end 0.12065 -0.305054)
			(stroke
				(width 0.1)
				(type default)
			)
			(layer "B.Fab")
		)
		(pad "1" smd circle
			(at 0.40005 0 90)
			(size 0 0)
			(layers "B.Cu" "B.Mask" "B.Paste")
			(net "PVNN_TERM_CPU1")
		)
		(pad "2" smd circle
			(at -0.40005 0 90)
			(size 0 0)
			(layers "B.Cu" "B.Mask" "B.Paste")
			(net "JTAG_MUX_CPU1_GTL_TDI")
		)
	)
	(footprint ""
		(layer "B.Cu")
		(at 254.508 -96.738948 180)
		(property "Reference" "R3642"
			(at 0 0 0)
			(layer "B.SilkS")
			(hide yes)
			(effects
				(font
					(size 1.27 1.27)
				)
				(justify mirror)
			)
		)
		(property "Value" ""
			(at 0 0 0)
			(layer "B.Fab")
			(effects
				(font
					(size 1.27 1.27)
				)
				(justify mirror)
			)
		)
		(duplicate_pad_numbers_are_jumpers no)
		(fp_line
			(start 0.7874 0.4064)
			(end 0.7874 -0.4064)
			(stroke
				(width 0.1524)
				(type default)
			)
			(layer "B.SilkS")
		)
		(fp_line
			(start 0.7874 -0.4064)
			(end -0.7874 -0.4064)
			(stroke
				(width 0.1524)
				(type default)
			)
			(layer "B.SilkS")
		)
		(fp_line
			(start -0.7874 0.4064)
			(end 0.7874 0.4064)
			(stroke
				(width 0.1524)
				(type default)
			)
			(layer "B.SilkS")
		)
		(fp_line
			(start -0.7874 -0.4064)
			(end -0.7874 0.4064)
			(stroke
				(width 0.1524)
				(type default)
			)
			(layer "B.SilkS")
		)
		(fp_line
			(start 0.67945 0.3048)
			(end 0.67945 -0.305054)
			(stroke
				(width 0.1)
				(type default)
			)
			(layer "B.Fab")
		)
		(fp_line
			(start 0.67945 -0.305054)
			(end 0.12065 -0.305054)
			(stroke
				(width 0.1)
				(type default)
			)
			(layer "B.Fab")
		)
		(fp_line
			(start 0.12065 0.3048)
			(end 0.67945 0.3048)
			(stroke
				(width 0.1)
				(type default)
			)
			(layer "B.Fab")
		)
		(fp_line
			(start 0.12065 0.2794)
			(end 0.12065 0.3048)
			(stroke
				(width 0.1)
				(type default)
			)
			(layer "B.Fab")
		)
		(fp_line
			(start 0.12065 -0.2794)
			(end -0.12065 -0.2794)
			(stroke
				(width 0.1)
				(type default)
			)
			(layer "B.Fab")
		)
		(fp_line
			(start 0.12065 -0.305054)
			(end 0.12065 -0.2794)
			(stroke
				(width 0.1)
				(type default)
			)
			(layer "B.Fab")
		)
		(fp_line
			(start -0.120396 0.3048)
			(end -0.120396 0.2794)
			(stroke
				(width 0.1)
				(type default)
			)
			(layer "B.Fab")
		)
		(fp_line
			(start -0.120396 0.2794)
			(end 0.12065 0.2794)
			(stroke
				(width 0.1)
				(type default)
			)
			(layer "B.Fab")
		)
		(fp_line
			(start -0.12065 -0.2794)
			(end -0.12065 -0.3048)
			(stroke
				(width 0.1)
				(type default)
			)
			(layer "B.Fab")
		)
		(fp_line
			(start -0.12065 -0.3048)
			(end -0.67945 -0.3048)
			(stroke
				(width 0.1)
				(type default)
			)
			(layer "B.Fab")
		)
		(fp_line
			(start -0.67945 0.3048)
			(end -0.120396 0.3048)
			(stroke
				(width 0.1)
				(type default)
			)
			(layer "B.Fab")
		)
		(fp_line
			(start -0.67945 -0.3048)
			(end -0.67945 0.3048)
			(stroke
				(width 0.1)
				(type default)
			)
			(layer "B.Fab")
		)
		(pad "1" smd circle
			(at 0.40005 0)
			(size 0 0)
			(layers "B.Cu" "B.Mask" "B.Paste")
			(net "P3V3_AUX")
		)
		(pad "2" smd circle
			(at -0.40005 0)
			(size 0 0)
			(layers "B.Cu" "B.Mask" "B.Paste")
			(net "CK440Q_OE_5")
		)
	)
)
